# BASEBOARD_FAB2 (Tioga Pass) — schematic netlist excerpt (pin names and nets, part order shuffled) for the footprints in the layout excerpt that follows; sources: Cadence DE-HDL packaged netlist, KiCad conversion of Wiwynn_Tioga_Pass_MB.brd

R3N26  RES  33.2 1% CHIP  pkg 0402  page 146 : A = LPC_LAD0_IO0 ; B = LPC_LAD0_IO0_R

(kicad_pcb
	(version 20260206)
	(generator "pcbnew")
	(generator_version "10.0")
	(general
		(thickness 1.6)
		(legacy_teardrops no)
	)
	(paper "A4")
	(title_block
		(title "Wiwynn_Tioga_Pass_MB.brd")
		(comment 1 "Tioga Pass / footprints 1726-1726 of 4770")
	)
	(layers
		(0 "F.Cu" signal "TOP")
		(4 "In1.Cu" signal "L2GND")
		(6 "In2.Cu" signal "L3")
		(8 "In3.Cu" signal "L4GND")
		(10 "In4.Cu" signal "L5")
		(12 "In5.Cu" signal "L6GND")
		(14 "In6.Cu" signal "L7VCC")
		(16 "In7.Cu" signal "L8VCC")
		(18 "In8.Cu" signal "L9GND")
		(20 "In9.Cu" signal "L10")
		(22 "In10.Cu" signal "L11GND")
		(24 "In11.Cu" signal "L12")
		(26 "In12.Cu" signal "L13GND")
		(2 "B.Cu" signal "BOTTOM")
		(9 "F.Adhes" user "F.Adhesive")
		(11 "B.Adhes" user "B.Adhesive")
		(13 "F.Paste" user "Package Geometry/Pastemask Top")
		(15 "B.Paste" user "Package Geometry/Pastemask Bottom")
		(5 "F.SilkS" user "Ref Des/Silkscreen Top")
		(7 "B.SilkS" user "Ref Des/Silkscreen Bottom")
		(1 "F.Mask" user "Board Geometry/Soldermask Top")
		(3 "B.Mask" user "Board Geometry/Soldermask Bottom")
		(17 "Dwgs.User" user "User.Drawings")
		(19 "Cmts.User" user "User.Comments")
		(21 "Eco1.User" user "User.Eco1")
		(23 "Eco2.User" user "User.Eco2")
		(25 "Edge.Cuts" user "Board Geometry/Outline")
		(27 "Margin" user)
		(31 "F.CrtYd" user "Package Geometry/Place Bound Top")
		(29 "B.CrtYd" user "Package Geometry/Place Bound Bottom")
		(35 "F.Fab" user "Ref Des/Assembly Top")
		(33 "B.Fab" user "Ref Des/Assembly Bottom")
	)
	(footprint ""
		(layer "F.Cu")
		(at 381.508 -88.2015)
		(property "Reference" "R3N26"
			(at 0 0 0)
			(layer "F.SilkS")
			(hide yes)
			(effects
				(font
					(size 1.27 1.27)
				)
			)
		)
		(property "Value" ""
			(at 0 0 0)
			(layer "F.Fab")
			(effects
				(font
					(size 1.27 1.27)
				)
			)
		)
		(duplicate_pad_numbers_are_jumpers no)
		(fp_poly
			(pts
				(xy -0.2794 -0.1016) (xy 0.2794 -0.1016) (xy 0.2794 0.9906) (xy -0.2794 0.9906)
			)
			(stroke
				(width 0)
				(type default)
			)
			(fill no)
			(layer "F.CrtYd")
		)
		(fp_line
			(start -0.2794 -0.1016)
			(end -0.2794 0.9906)
			(stroke
				(width 0.1)
				(type default)
			)
			(layer "F.Fab")
		)
		(fp_line
			(start -0.2794 0.9906)
			(end 0.2794 0.9906)
			(stroke
				(width 0.1)
				(type default)
			)
			(layer "F.Fab")
		)
		(fp_line
			(start 0.2794 -0.1016)
			(end -0.2794 -0.1016)
			(stroke
				(width 0.1)
				(type default)
			)
			(layer "F.Fab")
		)
		(fp_line
			(start 0.2794 0.9906)
			(end 0.2794 -0.1016)
			(stroke
				(width 0.1)
				(type default)
			)
			(layer "F.Fab")
		)
		(pad "1" smd rect
			(at 0 0)
			(size 0.508 0.508)
			(layers "F.Cu" "F.Mask" "F.Paste")
			(net "LPC_LAD0_IO0")
		)
		(pad "2" smd rect
			(at 0 0.889)
			(size 0.508 0.508)
			(layers "F.Cu" "F.Mask" "F.Paste")
			(net "LPC_LAD0_IO0_R")
		)
		(zone
			(layer "F.Cu")
			(hatch none 0.5)
			(connect_pads
				(clearance 0)
			)
			(min_thickness 0.25)
			(keepout
				(tracks allowed)
				(vias not_allowed)
				(pads allowed)
				(copperpour not_allowed)
				(footprints allowed)
			)
			(placement
				(enabled no)
				(sheetname "")
			)
			(fill
				(thermal_gap 0.5)
				(thermal_bridge_width 0.5)
				(island_removal_mode 0)
			)
			(polygon
				(pts
					(xy 381.254 -87.9475) (xy 381.762 -87.9475) (xy 381.762 -87.5665) (xy 381.254 -87.5665)
				)
			)
		)
		(zone
			(layer "F.Cu")
			(hatch none 0.5)
			(connect_pads
				(clearance 0)
			)
			(min_thickness 0.25)
			(keepout
				(tracks not_allowed)
				(vias allowed)
				(pads allowed)
				(copperpour not_allowed)
				(footprints allowed)
			)
			(placement
				(enabled no)
				(sheetname "")
			)
			(fill
				(thermal_gap 0.5)
				(thermal_bridge_width 0.5)
				(island_removal_mode 0)
			)
			(polygon
				(pts
					(xy 381.254 -87.5665) (xy 381.762 -87.5665) (xy 381.762 -87.9475) (xy 381.254 -87.9475)
				)
			)
		)
	)
)
